(kicad_pcb
	(version 20260206)
	(generator "pcbnew")
	(generator_version "10.0")
	(general
		(thickness 1.6)
		(legacy_teardrops no)
	)
	(paper "A4")
	(title_block
		(title "Bryce Canyon_LED_16347-1_OCP.brd")
		(comment 1 "Bryce Canyon / footprints 43-48 of 49")
	)
	(layers
		(0 "F.Cu" signal "TOP")
		(2 "B.Cu" signal "BOTTOM")
		(9 "F.Adhes" user "F.Adhesive")
		(11 "B.Adhes" user "B.Adhesive")
		(13 "F.Paste" user "Package Geometry/Pastemask Top")
		(15 "B.Paste" user "Package Geometry/Pastemask Bottom")
		(5 "F.SilkS" user "Ref Des/Silkscreen Top")
		(7 "B.SilkS" user "Ref Des/Silkscreen Bottom")
		(1 "F.Mask" user "Board Geometry/Soldermask Top")
		(3 "B.Mask" user "Board Geometry/Soldermask Bottom")
		(17 "Dwgs.User" user "User.Drawings")
		(19 "Cmts.User" user "User.Comments")
		(21 "Eco1.User" user "User.Eco1")
		(23 "Eco2.User" user "User.Eco2")
		(25 "Edge.Cuts" user "Board Geometry/Outline")
		(27 "Margin" user)
		(31 "F.CrtYd" user "Package Geometry/Place Bound Top")
		(29 "B.CrtYd" user "Package Geometry/Place Bound Bottom")
		(35 "F.Fab" user "Ref Des/Assembly Top")
		(33 "B.Fab" user "Ref Des/Assembly Bottom")
	)
	(footprint ""
		(layer "B.Cu")
		(at 142.24 -3.302 -90)
		(property "Reference" "R22"
			(at 0 0 90)
			(layer "B.SilkS")
			(hide yes)
			(effects
				(font
					(size 1.27 1.27)
				)
				(justify mirror)
			)
		)
		(property "Value" "4K7R2F-GP"
			(at -0.064008 -3.993896 270)
			(unlocked yes)
			(layer "B.Fab")
			(hide yes)
			(effects
				(font
					(size 1.016 1.016)
					(thickness 0.1524)
				)
				(justify mirror)
			)
		)
		(property "Device Type" "R402H16"
			(at -0.064008 -5.517896 270)
			(unlocked yes)
			(layer "B.Fab")
			(hide yes)
			(effects
				(font
					(size 1.016 1.016)
					(thickness 0.1524)
				)
				(justify mirror)
			)
		)
		(duplicate_pad_numbers_are_jumpers no)
		(fp_line
			(start -0.508 -0.9398)
			(end 0.508 -0.9398)
			(stroke
				(width 0.1524)
				(type default)
			)
			(layer "B.SilkS")
		)
		(fp_line
			(start 0.508 -0.9398)
			(end 0.508 0.9398)
			(stroke
				(width 0.1524)
				(type default)
			)
			(layer "B.SilkS")
		)
		(fp_rect
			(start 0.508 0.9398)
			(end -0.508 -0.9398)
			(stroke
				(width 0)
				(type default)
			)
			(fill no)
			(layer "B.CrtYd")
		)
		(fp_rect
			(start 0.508 0.9398)
			(end -0.508 -0.9398)
			(stroke
				(width 0)
				(type default)
			)
			(fill no)
			(layer "B.Fab")
		)
		(pad "1" smd custom
			(at 0 -0.4445 90)
			(size 0.1397 0.1397)
			(layers "B.Cu" "B.Mask" "B.Paste")
			(net "DRIVE_A_28_34_ACT")
			(options
				(clearance outline)
				(anchor circle)
			)
			(primitives
				(gr_poly
					(pts
						(arc
							(start -0.1778 0.2794)
							(mid -0.249642 0.249642)
							(end -0.2794 0.1778)
						)
						(arc
							(start -0.2794 -0.1778)
							(mid -0.249642 -0.249642)
							(end -0.1778 -0.2794)
						)
						(arc
							(start 0.1778 -0.2794)
							(mid 0.249642 -0.249642)
							(end 0.2794 -0.1778)
						)
						(arc
							(start 0.2794 0.1778)
							(mid 0.249642 0.249642)
							(end 0.1778 0.2794)
						)
					)
					(width 0)
					(fill yes)
				)
			)
		)
		(pad "2" smd custom
			(at 0 0.4445 90)
			(size 0.1397 0.1397)
			(layers "B.Cu" "B.Mask" "B.Paste")
			(net "GND")
			(options
				(clearance outline)
				(anchor circle)
			)
			(primitives
				(gr_poly
					(pts
						(arc
							(start -0.1778 0.2794)
							(mid -0.249642 0.249642)
							(end -0.2794 0.1778)
						)
						(arc
							(start -0.2794 -0.1778)
							(mid -0.249642 -0.249642)
							(end -0.1778 -0.2794)
						)
						(arc
							(start 0.1778 -0.2794)
							(mid 0.249642 -0.249642)
							(end 0.2794 -0.1778)
						)
						(arc
							(start 0.2794 0.1778)
							(mid 0.249642 0.249642)
							(end 0.1778 0.2794)
						)
					)
					(width 0)
					(fill yes)
				)
			)
		)
	)
	(footprint ""
		(layer "B.Cu")
		(at 18.7198 -5.4102)
		(property "Reference" "Q1"
			(at 0 0 0)
			(layer "B.SilkS")
			(hide yes)
			(effects
				(font
					(size 1.27 1.27)
				)
				(justify mirror)
			)
		)
		(property "Value" "2N7002K-2-GP"
			(at -0.127 -8.9662 0)
			(unlocked yes)
			(layer "B.Fab")
			(hide yes)
			(effects
				(font
					(size 1.016 1.016)
					(thickness 0.1524)
				)
				(justify mirror)
			)
		)
		(property "Device Type" "SOT23DGS2D4H44"
			(at -0.127 -10.4902 0)
			(unlocked yes)
			(layer "B.Fab")
			(hide yes)
			(effects
				(font
					(size 1.016 1.016)
					(thickness 0.1524)
				)
				(justify mirror)
			)
		)
		(duplicate_pad_numbers_are_jumpers no)
		(fp_line
			(start -1.651 -1.778)
			(end 1.651 -1.778)
			(stroke
				(width 0.1524)
				(type default)
			)
			(layer "B.SilkS")
		)
		(fp_line
			(start -1.651 1.778)
			(end -1.651 -1.778)
			(stroke
				(width 0.1524)
				(type default)
			)
			(layer "B.SilkS")
		)
		(fp_line
			(start 1.651 -1.778)
			(end 1.651 1.778)
			(stroke
				(width 0.1524)
				(type default)
			)
			(layer "B.SilkS")
		)
		(fp_line
			(start 1.651 1.778)
			(end -1.651 1.778)
			(stroke
				(width 0.1524)
				(type default)
			)
			(layer "B.SilkS")
		)
		(fp_poly
			(pts
				(xy 1.778 1.8796) (xy 1.778 -1.8796) (xy -1.778 -1.8796) (xy -1.778 1.8796)
			)
			(stroke
				(width 0)
				(type default)
			)
			(fill no)
			(layer "B.CrtYd")
		)
		(fp_poly
			(pts
				(xy 1.778 1.8796) (xy 1.778 -1.8796) (xy -1.778 -1.8796) (xy -1.778 1.8796)
			)
			(stroke
				(width 0)
				(type default)
			)
			(fill no)
			(layer "B.Fab")
		)
		(pad "D" smd custom
			(at 0 -0.9525 180)
			(size 0.1905 0.1905)
			(layers "B.Cu" "B.Mask" "B.Paste")
			(net "FLT_HDD24_30_N")
			(options
				(clearance outline)
				(anchor circle)
			)
			(primitives
				(gr_poly
					(pts
						(arc
							(start -0.1778 -0.5715)
							(mid -0.321484 -0.511984)
							(end -0.381 -0.3683)
						)
						(arc
							(start -0.381 0.3683)
							(mid -0.321484 0.511984)
							(end -0.1778 0.5715)
						)
						(arc
							(start 0.1778 0.5715)
							(mid 0.321484 0.511984)
							(end 0.381 0.3683)
						)
						(arc
							(start 0.381 -0.3683)
							(mid 0.321484 -0.511984)
							(end 0.1778 -0.5715)
						)
					)
					(width 0)
					(fill yes)
				)
			)
		)
		(pad "G" smd custom
			(at 0.98425 0.9525 180)
			(size 0.1905 0.1905)
			(layers "B.Cu" "B.Mask" "B.Paste")
			(net "DRIVE_A_24_30_FLT_LED")
			(options
				(clearance outline)
				(anchor circle)
			)
			(primitives
				(gr_poly
					(pts
						(arc
							(start -0.1778 -0.5715)
							(mid -0.321484 -0.511984)
							(end -0.381 -0.3683)
						)
						(arc
							(start -0.381 0.3683)
							(mid -0.321484 0.511984)
							(end -0.1778 0.5715)
						)
						(arc
							(start 0.1778 0.5715)
							(mid 0.321484 0.511984)
							(end 0.381 0.3683)
						)
						(arc
							(start 0.381 -0.3683)
							(mid 0.321484 -0.511984)
							(end 0.1778 -0.5715)
						)
					)
					(width 0)
					(fill yes)
				)
			)
		)
		(pad "S" smd custom
			(at -0.98425 0.9525 180)
			(size 0.1905 0.1905)
			(layers "B.Cu" "B.Mask" "B.Paste")
			(net "GND")
			(options
				(clearance outline)
				(anchor circle)
			)
			(primitives
				(gr_poly
					(pts
						(arc
							(start -0.1778 -0.5715)
							(mid -0.321484 -0.511984)
							(end -0.381 -0.3683)
						)
						(arc
							(start -0.381 0.3683)
							(mid -0.321484 0.511984)
							(end -0.1778 0.5715)
						)
						(arc
							(start 0.1778 0.5715)
							(mid 0.321484 0.511984)
							(end 0.381 0.3683)
						)
						(arc
							(start 0.381 -0.3683)
							(mid 0.321484 -0.511984)
							(end 0.1778 -0.5715)
						)
					)
					(width 0)
					(fill yes)
				)
			)
		)
	)
	(footprint ""
		(layer "B.Cu")
		(at 26.0604 -5.9436 180)
		(property "Reference" "R3"
			(at 0 0 0)
			(layer "B.SilkS")
			(hide yes)
			(effects
				(font
					(size 1.27 1.27)
				)
				(justify mirror)
			)
		)
		(property "Value" "130R3F-GP"
			(at 0.0254 -2.5146 180)
			(unlocked yes)
			(layer "B.Fab")
			(hide yes)
			(effects
				(font
					(size 1.016 1.016)
					(thickness 0.1524)
				)
				(justify mirror)
			)
		)
		(property "Device Type" "R603H22"
			(at 0.0254 -4.0386 180)
			(unlocked yes)
			(layer "B.Fab")
			(hide yes)
			(effects
				(font
					(size 1.016 1.016)
					(thickness 0.1524)
				)
				(justify mirror)
			)
		)
		(duplicate_pad_numbers_are_jumpers no)
		(fp_line
			(start 0.4826 0)
			(end 0.2032 0)
			(stroke
				(width 0.2032)
				(type default)
			)
			(layer "B.SilkS")
		)
		(fp_line
			(start -0.2032 0)
			(end -0.4826 0)
			(stroke
				(width 0.2032)
				(type default)
			)
			(layer "B.SilkS")
		)
		(fp_rect
			(start 0.5842 1.3335)
			(end -0.5842 -1.3335)
			(stroke
				(width 0)
				(type default)
			)
			(fill no)
			(layer "B.CrtYd")
		)
		(fp_rect
			(start 0.5842 1.3335)
			(end -0.5842 -1.3335)
			(stroke
				(width 0)
				(type default)
			)
			(fill no)
			(layer "B.Fab")
		)
		(pad "1" smd custom
			(at 0 -0.762)
			(size 0.2159 0.2159)
			(layers "B.Cu" "B.Mask" "B.Paste")
			(net "P5V_A")
			(options
				(clearance outline)
				(anchor circle)
			)
			(primitives
				(gr_poly
					(pts
						(arc
							(start -0.3302 0.4318)
							(mid -0.402042 0.402042)
							(end -0.4318 0.3302)
						)
						(arc
							(start -0.4318 -0.3302)
							(mid -0.402042 -0.402042)
							(end -0.3302 -0.4318)
						)
						(arc
							(start 0.3302 -0.4318)
							(mid 0.402042 -0.402042)
							(end 0.4318 -0.3302)
						)
						(arc
							(start 0.4318 0.3302)
							(mid 0.402042 0.402042)
							(end 0.3302 0.4318)
						)
					)
					(width 0)
					(fill yes)
				)
			)
		)
		(pad "2" smd custom
			(at 0 0.762)
			(size 0.2159 0.2159)
			(layers "B.Cu" "B.Mask" "B.Paste")
			(net "FLT_HDD25_31")
			(options
				(clearance outline)
				(anchor circle)
			)
			(primitives
				(gr_poly
					(pts
						(arc
							(start -0.3302 0.4318)
							(mid -0.402042 0.402042)
							(end -0.4318 0.3302)
						)
						(arc
							(start -0.4318 -0.3302)
							(mid -0.402042 -0.402042)
							(end -0.3302 -0.4318)
						)
						(arc
							(start 0.3302 -0.4318)
							(mid 0.402042 -0.402042)
							(end 0.4318 -0.3302)
						)
						(arc
							(start 0.4318 0.3302)
							(mid 0.402042 0.402042)
							(end 0.3302 0.4318)
						)
					)
					(width 0)
					(fill yes)
				)
			)
		)
	)
	(footprint ""
		(layer "B.Cu")
		(at 144.4752 -5.8928 180)
		(property "Reference" "R10"
			(at 0 0 0)
			(layer "B.SilkS")
			(hide yes)
			(effects
				(font
					(size 1.27 1.27)
				)
				(justify mirror)
			)
		)
		(property "Value" "91R3F-1-GP"
			(at 0.0254 -2.5146 180)
			(unlocked yes)
			(layer "B.Fab")
			(hide yes)
			(effects
				(font
					(size 1.016 1.016)
					(thickness 0.1524)
				)
				(justify mirror)
			)
		)
		(property "Device Type" "R603H22"
			(at 0.0254 -4.0386 180)
			(unlocked yes)
			(layer "B.Fab")
			(hide yes)
			(effects
				(font
					(size 1.016 1.016)
					(thickness 0.1524)
				)
				(justify mirror)
			)
		)
		(duplicate_pad_numbers_are_jumpers no)
		(fp_line
			(start 0.4826 0)
			(end 0.2032 0)
			(stroke
				(width 0.2032)
				(type default)
			)
			(layer "B.SilkS")
		)
		(fp_line
			(start -0.2032 0)
			(end -0.4826 0)
			(stroke
				(width 0.2032)
				(type default)
			)
			(layer "B.SilkS")
		)
		(fp_rect
			(start 0.5842 1.3335)
			(end -0.5842 -1.3335)
			(stroke
				(width 0)
				(type default)
			)
			(fill no)
			(layer "B.CrtYd")
		)
		(fp_rect
			(start 0.5842 1.3335)
			(end -0.5842 -1.3335)
			(stroke
				(width 0)
				(type default)
			)
			(fill no)
			(layer "B.Fab")
		)
		(pad "1" smd custom
			(at 0 -0.762)
			(size 0.2159 0.2159)
			(layers "B.Cu" "B.Mask" "B.Paste")
			(net "P5V_A")
			(options
				(clearance outline)
				(anchor circle)
			)
			(primitives
				(gr_poly
					(pts
						(arc
							(start -0.3302 0.4318)
							(mid -0.402042 0.402042)
							(end -0.4318 0.3302)
						)
						(arc
							(start -0.4318 -0.3302)
							(mid -0.402042 -0.402042)
							(end -0.3302 -0.4318)
						)
						(arc
							(start 0.3302 -0.4318)
							(mid 0.402042 -0.402042)
							(end 0.4318 -0.3302)
						)
						(arc
							(start 0.4318 0.3302)
							(mid 0.402042 0.402042)
							(end 0.3302 0.4318)
						)
					)
					(width 0)
					(fill yes)
				)
			)
		)
		(pad "2" smd custom
			(at 0 0.762)
			(size 0.2159 0.2159)
			(layers "B.Cu" "B.Mask" "B.Paste")
			(net "DRV_ACT_28_34")
			(options
				(clearance outline)
				(anchor circle)
			)
			(primitives
				(gr_poly
					(pts
						(arc
							(start -0.3302 0.4318)
							(mid -0.402042 0.402042)
							(end -0.4318 0.3302)
						)
						(arc
							(start -0.4318 -0.3302)
							(mid -0.402042 -0.402042)
							(end -0.3302 -0.4318)
						)
						(arc
							(start 0.3302 -0.4318)
							(mid 0.402042 -0.402042)
							(end 0.4318 -0.3302)
						)
						(arc
							(start 0.4318 0.3302)
							(mid 0.402042 0.402042)
							(end 0.3302 0.4318)
						)
					)
					(width 0)
					(fill yes)
				)
			)
		)
	)
	(footprint ""
		(layer "B.Cu")
		(at 68.378578 -5.652516)
		(property "Reference" "Q5"
			(at 0 0 0)
			(layer "B.SilkS")
			(hide yes)
			(effects
				(font
					(size 1.27 1.27)
				)
				(justify mirror)
			)
		)
		(property "Value" "2N7002K-2-GP"
			(at -0.127 -8.9662 0)
			(unlocked yes)
			(layer "B.Fab")
			(hide yes)
			(effects
				(font
					(size 1.016 1.016)
					(thickness 0.1524)
				)
				(justify mirror)
			)
		)
		(property "Device Type" "SOT23DGS2D4H44"
			(at -0.127 -10.4902 0)
			(unlocked yes)
			(layer "B.Fab")
			(hide yes)
			(effects
				(font
					(size 1.016 1.016)
					(thickness 0.1524)
				)
				(justify mirror)
			)
		)
		(duplicate_pad_numbers_are_jumpers no)
		(fp_line
			(start -1.651 -1.778)
			(end 1.651 -1.778)
			(stroke
				(width 0.1524)
				(type default)
			)
			(layer "B.SilkS")
		)
		(fp_line
			(start -1.651 1.778)
			(end -1.651 -1.778)
			(stroke
				(width 0.1524)
				(type default)
			)
			(layer "B.SilkS")
		)
		(fp_line
			(start 1.651 -1.778)
			(end 1.651 1.778)
			(stroke
				(width 0.1524)
				(type default)
			)
			(layer "B.SilkS")
		)
		(fp_line
			(start 1.651 1.778)
			(end -1.651 1.778)
			(stroke
				(width 0.1524)
				(type default)
			)
			(layer "B.SilkS")
		)
		(fp_poly
			(pts
				(xy 1.778 1.8796) (xy 1.778 -1.8796) (xy -1.778 -1.8796) (xy -1.778 1.8796)
			)
			(stroke
				(width 0)
				(type default)
			)
			(fill no)
			(layer "B.CrtYd")
		)
		(fp_poly
			(pts
				(xy 1.778 1.8796) (xy 1.778 -1.8796) (xy -1.778 -1.8796) (xy -1.778 1.8796)
			)
			(stroke
				(width 0)
				(type default)
			)
			(fill no)
			(layer "B.Fab")
		)
		(pad "D" smd custom
			(at 0 -0.9525 180)
			(size 0.1905 0.1905)
			(layers "B.Cu" "B.Mask" "B.Paste")
			(net "FLT_HDD26_32_N")
			(options
				(clearance outline)
				(anchor circle)
			)
			(primitives
				(gr_poly
					(pts
						(arc
							(start -0.1778 -0.5715)
							(mid -0.321484 -0.511984)
							(end -0.381 -0.3683)
						)
						(arc
							(start -0.381 0.3683)
							(mid -0.321484 0.511984)
							(end -0.1778 0.5715)
						)
						(arc
							(start 0.1778 0.5715)
							(mid 0.321484 0.511984)
							(end 0.381 0.3683)
						)
						(arc
							(start 0.381 -0.3683)
							(mid 0.321484 -0.511984)
							(end 0.1778 -0.5715)
						)
					)
					(width 0)
					(fill yes)
				)
			)
		)
		(pad "G" smd custom
			(at 0.98425 0.9525 180)
			(size 0.1905 0.1905)
			(layers "B.Cu" "B.Mask" "B.Paste")
			(net "DRIVE_A_26_32_FLT_LED")
			(options
				(clearance outline)
				(anchor circle)
			)
			(primitives
				(gr_poly
					(pts
						(arc
							(start -0.1778 -0.5715)
							(mid -0.321484 -0.511984)
							(end -0.381 -0.3683)
						)
						(arc
							(start -0.381 0.3683)
							(mid -0.321484 0.511984)
							(end -0.1778 0.5715)
						)
						(arc
							(start 0.1778 0.5715)
							(mid 0.321484 0.511984)
							(end 0.381 0.3683)
						)
						(arc
							(start 0.381 -0.3683)
							(mid 0.321484 -0.511984)
							(end 0.1778 -0.5715)
						)
					)
					(width 0)
					(fill yes)
				)
			)
		)
		(pad "S" smd custom
			(at -0.98425 0.9525 180)
			(size 0.1905 0.1905)
			(layers "B.Cu" "B.Mask" "B.Paste")
			(net "GND")
			(options
				(clearance outline)
				(anchor circle)
			)
			(primitives
				(gr_poly
					(pts
						(arc
							(start -0.1778 -0.5715)
							(mid -0.321484 -0.511984)
							(end -0.381 -0.3683)
						)
						(arc
							(start -0.381 0.3683)
							(mid -0.321484 0.511984)
							(end -0.1778 0.5715)
						)
						(arc
							(start 0.1778 0.5715)
							(mid 0.321484 0.511984)
							(end 0.381 0.3683)
						)
						(arc
							(start 0.381 -0.3683)
							(mid 0.321484 -0.511984)
							(end 0.1778 -0.5715)
						)
					)
					(width 0)
					(fill yes)
				)
			)
		)
	)
	(footprint ""
		(layer "B.Cu")
		(at 110.2106 -3.5052 -90)
		(property "Reference" "R20"
			(at 0 0 90)
			(layer "B.SilkS")
			(hide yes)
			(effects
				(font
					(size 1.27 1.27)
				)
				(justify mirror)
			)
		)
		(property "Value" "4K7R2F-GP"
			(at -0.064008 -3.993896 270)
			(unlocked yes)
			(layer "B.Fab")
			(hide yes)
			(effects
				(font
					(size 1.016 1.016)
					(thickness 0.1524)
				)
				(justify mirror)
			)
		)
		(property "Device Type" "R402H16"
			(at -0.064008 -5.517896 270)
			(unlocked yes)
			(layer "B.Fab")
			(hide yes)
			(effects
				(font
					(size 1.016 1.016)
					(thickness 0.1524)
				)
				(justify mirror)
			)
		)
		(duplicate_pad_numbers_are_jumpers no)
		(fp_line
			(start -0.508 -0.9398)
			(end 0.508 -0.9398)
			(stroke
				(width 0.1524)
				(type default)
			)
			(layer "B.SilkS")
		)
		(fp_line
			(start 0.508 -0.9398)
			(end 0.508 0.9398)
			(stroke
				(width 0.1524)
				(type default)
			)
			(layer "B.SilkS")
		)
		(fp_rect
			(start 0.508 0.9398)
			(end -0.508 -0.9398)
			(stroke
				(width 0)
				(type default)
			)
			(fill no)
			(layer "B.CrtYd")
		)
		(fp_rect
			(start 0.508 0.9398)
			(end -0.508 -0.9398)
			(stroke
				(width 0)
				(type default)
			)
			(fill no)
			(layer "B.Fab")
		)
		(pad "1" smd custom
			(at 0 -0.4445 90)
			(size 0.1397 0.1397)
			(layers "B.Cu" "B.Mask" "B.Paste")
			(net "DRIVE_A_27_33_ACT")
			(options
				(clearance outline)
				(anchor circle)
			)
			(primitives
				(gr_poly
					(pts
						(arc
							(start -0.1778 0.2794)
							(mid -0.249642 0.249642)
							(end -0.2794 0.1778)
						)
						(arc
							(start -0.2794 -0.1778)
							(mid -0.249642 -0.249642)
							(end -0.1778 -0.2794)
						)
						(arc
							(start 0.1778 -0.2794)
							(mid 0.249642 -0.249642)
							(end 0.2794 -0.1778)
						)
						(arc
							(start 0.2794 0.1778)
							(mid 0.249642 0.249642)
							(end 0.1778 0.2794)
						)
					)
					(width 0)
					(fill yes)
				)
			)
		)
		(pad "2" smd custom
			(at 0 0.4445 90)
			(size 0.1397 0.1397)
			(layers "B.Cu" "B.Mask" "B.Paste")
			(net "GND")
			(options
				(clearance outline)
				(anchor circle)
			)
			(primitives
				(gr_poly
					(pts
						(arc
							(start -0.1778 0.2794)
							(mid -0.249642 0.249642)
							(end -0.2794 0.1778)
						)
						(arc
							(start -0.2794 -0.1778)
							(mid -0.249642 -0.249642)
							(end -0.1778 -0.2794)
						)
						(arc
							(start 0.1778 -0.2794)
							(mid 0.249642 -0.249642)
							(end 0.2794 -0.1778)
						)
						(arc
							(start 0.2794 0.1778)
							(mid 0.249642 0.249642)
							(end 0.1778 0.2794)
						)
					)
					(width 0)
					(fill yes)
				)
			)
		)
	)
)
